(kicad_pcb
	(version 20260206)
	(generator "pcbnew")
	(generator_version "10.0")
	(general
		(thickness 1.21888)
		(legacy_teardrops no)
	)
	(paper "A4")
	(title_block
		(title "timecard-beta-v1 — TimeCard-DC-V1.PcbDoc")
		(comment 1 "Time Appliance Project (Time Card) / footprint 22 of 120 (P1), pads 1-133 of 340")
	)
	(layers
		(0 "F.Cu" signal "TOP")
		(4 "In1.Cu" signal "SGND")
		(6 "In2.Cu" signal "IN1")
		(8 "In3.Cu" signal "IN2")
		(10 "In4.Cu" signal "SGND1")
		(2 "B.Cu" signal "BOTTOM")
		(9 "F.Adhes" user "F.Adhesive")
		(11 "B.Adhes" user "B.Adhesive")
		(13 "F.Paste" user "Top Paste")
		(15 "B.Paste" user "Bottom Paste")
		(5 "F.SilkS" user "Top Overlay")
		(7 "B.SilkS" user "Bottom Overlay")
		(1 "F.Mask" user "Top Solder")
		(3 "B.Mask" user "Bottom Solder")
		(17 "Dwgs.User" user "User.Drawings")
		(19 "Cmts.User" user "User.Comments")
		(21 "Eco1.User" user "User.Eco1")
		(23 "Eco2.User" user "User.Eco2")
		(25 "Edge.Cuts" user)
		(27 "Margin" user)
		(31 "F.CrtYd" user "Top Courtyard")
		(29 "B.CrtYd" user "Bottom Courtyard")
		(35 "F.Fab" user "Top Component Center")
		(33 "B.Fab" user "Bottom Component Center")
	)
	(footprint "FPGA_CONN:FPGA_CONN"
		(locked yes)
		(layer "F.Cu")
		(at 125.389655 117.4386)
		(property "Reference" "P1"
			(at -27.35726 -23.265455 0)
			(unlocked yes)
			(layer "F.SilkS")
			(effects
				(font
					(size 0.762 0.762)
					(thickness 0.2286)
				)
				(justify left bottom)
			)
		)
		(property "Value" "FPGA_CONN"
			(at -43.9575 52.70297 0)
			(unlocked yes)
			(layer "F.SilkS")
			(hide yes)
			(effects
				(font
					(size 1.524 1.524)
					(thickness 0.254)
				)
				(justify left bottom)
			)
		)
		(sheetname "FPGA")
		(sheetfile "FPGA.kicad_sch")
		(duplicate_pad_numbers_are_jumpers no)
		(pad "A-1" smd rect
			(at 21.78647 -9.87527)
			(size 1.54991 0.24994)
			(layers "F.Cu" "F.Mask" "F.Paste")
			(net "+5.0V")
		)
		(pad "A-2" smd rect
			(at 25.83624 -9.87527)
			(size 1.54991 0.24994)
			(layers "F.Cu" "F.Mask" "F.Paste")
			(net "+5.0V")
		)
		(pad "A-3" smd rect
			(at 21.78647 -9.37514)
			(size 1.54991 0.24994)
			(layers "F.Cu" "F.Mask" "F.Paste")
			(net "+5.0V")
		)
		(pad "A-4" smd rect
			(at 25.83624 -9.37514)
			(size 1.54991 0.24994)
			(layers "F.Cu" "F.Mask" "F.Paste")
			(net "+5.0V")
		)
		(pad "A-5" smd rect
			(at 21.78647 -8.87527)
			(size 1.54991 0.24994)
			(layers "F.Cu" "F.Mask" "F.Paste")
			(net "+5.0V")
		)
		(pad "A-6" smd rect
			(at 25.83624 -8.87527)
			(size 1.54991 0.24994)
			(layers "F.Cu" "F.Mask" "F.Paste")
			(net "+5.0V")
		)
		(pad "A-7" smd rect
			(at 21.78647 -8.37514)
			(size 1.54991 0.24994)
			(layers "F.Cu" "F.Mask" "F.Paste")
			(net "+5.0V")
		)
		(pad "A-8" smd rect
			(at 25.83624 -8.37514)
			(size 1.54991 0.24994)
			(layers "F.Cu" "F.Mask" "F.Paste")
			(net "+5.0V")
		)
		(pad "A-9" smd rect
			(at 21.78647 -7.87527)
			(size 1.54991 0.24994)
			(layers "F.Cu" "F.Mask" "F.Paste")
			(net "GND")
		)
		(pad "A-10" smd rect
			(at 25.83624 -7.87527)
			(size 1.54991 0.24994)
			(layers "F.Cu" "F.Mask" "F.Paste")
			(net "GND")
		)
		(pad "A-11" smd rect
			(at 21.78647 -7.37514)
			(size 1.54991 0.24994)
			(layers "F.Cu" "F.Mask" "F.Paste")
		)
		(pad "A-12" smd rect
			(at 25.83624 -7.37514)
			(size 1.54991 0.24994)
			(layers "F.Cu" "F.Mask" "F.Paste")
		)
		(pad "A-13" smd rect
			(at 21.78647 -6.87527)
			(size 1.54991 0.24994)
			(layers "F.Cu" "F.Mask" "F.Paste")
		)
		(pad "A-14" smd rect
			(at 25.83624 -6.87527)
			(size 1.54991 0.24994)
			(layers "F.Cu" "F.Mask" "F.Paste")
		)
		(pad "A-15" smd rect
			(at 21.78647 -6.37515)
			(size 1.54991 0.24994)
			(layers "F.Cu" "F.Mask" "F.Paste")
		)
		(pad "A-16" smd rect
			(at 25.83624 -6.37515)
			(size 1.54991 0.24994)
			(layers "F.Cu" "F.Mask" "F.Paste")
		)
		(pad "A-17" smd rect
			(at 21.78647 -5.87527)
			(size 1.54991 0.24994)
			(layers "F.Cu" "F.Mask" "F.Paste")
		)
		(pad "A-18" smd rect
			(at 25.83624 -5.87527)
			(size 1.54991 0.24994)
			(layers "F.Cu" "F.Mask" "F.Paste")
		)
		(pad "A-19" smd rect
			(at 21.78647 -5.37515)
			(size 1.54991 0.24994)
			(layers "F.Cu" "F.Mask" "F.Paste")
			(net "GND")
		)
		(pad "A-20" smd rect
			(at 25.83624 -5.37515)
			(size 1.54991 0.24994)
			(layers "F.Cu" "F.Mask" "F.Paste")
			(net "GND")
		)
		(pad "A-21" smd rect
			(at 21.78647 -4.87528)
			(size 1.54991 0.24994)
			(layers "F.Cu" "F.Mask" "F.Paste")
		)
		(pad "A-22" smd rect
			(at 25.83624 -4.87528)
			(size 1.54991 0.24994)
			(layers "F.Cu" "F.Mask" "F.Paste")
			(net "GPS1_RST")
		)
		(pad "A-23" smd rect
			(at 21.78647 -4.37515)
			(size 1.54991 0.24994)
			(layers "F.Cu" "F.Mask" "F.Paste")
		)
		(pad "A-24" smd rect
			(at 25.83624 -4.37515)
			(size 1.54991 0.24994)
			(layers "F.Cu" "F.Mask" "F.Paste")
		)
		(pad "A-25" smd rect
			(at 21.78647 -3.87528)
			(size 1.54991 0.24994)
			(layers "F.Cu" "F.Mask" "F.Paste")
		)
		(pad "A-26" smd rect
			(at 25.83624 -3.87528)
			(size 1.54991 0.24994)
			(layers "F.Cu" "F.Mask" "F.Paste")
		)
		(pad "A-27" smd rect
			(at 21.78647 -3.37515)
			(size 1.54991 0.24994)
			(layers "F.Cu" "F.Mask" "F.Paste")
		)
		(pad "A-28" smd rect
			(at 25.83624 -3.37515)
			(size 1.54991 0.24994)
			(layers "F.Cu" "F.Mask" "F.Paste")
		)
		(pad "A-29" smd rect
			(at 21.78647 -2.87528)
			(size 1.54991 0.24994)
			(layers "F.Cu" "F.Mask" "F.Paste")
			(net "GND")
		)
		(pad "A-30" smd rect
			(at 25.83624 -2.87528)
			(size 1.54991 0.24994)
			(layers "F.Cu" "F.Mask" "F.Paste")
			(net "GND")
		)
		(pad "A-31" smd rect
			(at 21.78647 -2.37515)
			(size 1.54991 0.24994)
			(layers "F.Cu" "F.Mask" "F.Paste")
		)
		(pad "A-32" smd rect
			(at 25.83624 -2.37515)
			(size 1.54991 0.24994)
			(layers "F.Cu" "F.Mask" "F.Paste")
			(net "GPS1_TP1")
		)
		(pad "A-33" smd rect
			(at 21.78647 -1.87528)
			(size 1.54991 0.24994)
			(layers "F.Cu" "F.Mask" "F.Paste")
		)
		(pad "A-34" smd rect
			(at 25.83624 -1.87528)
			(size 1.54991 0.24994)
			(layers "F.Cu" "F.Mask" "F.Paste")
			(net "GPS1_TP2")
		)
		(pad "A-35" smd rect
			(at 21.78647 -1.37516)
			(size 1.54991 0.24994)
			(layers "F.Cu" "F.Mask" "F.Paste")
		)
		(pad "A-36" smd rect
			(at 25.83624 -1.37516)
			(size 1.54991 0.24994)
			(layers "F.Cu" "F.Mask" "F.Paste")
		)
		(pad "A-37" smd rect
			(at 21.78647 -0.87528)
			(size 1.54991 0.24994)
			(layers "F.Cu" "F.Mask" "F.Paste")
		)
		(pad "A-38" smd rect
			(at 25.83624 -0.87528)
			(size 1.54991 0.24994)
			(layers "F.Cu" "F.Mask" "F.Paste")
		)
		(pad "A-39" smd rect
			(at 21.78647 -0.37516)
			(size 1.54991 0.24994)
			(layers "F.Cu" "F.Mask" "F.Paste")
			(net "GND")
		)
		(pad "A-40" smd rect
			(at 25.83624 -0.37516)
			(size 1.54991 0.24994)
			(layers "F.Cu" "F.Mask" "F.Paste")
			(net "GND")
		)
		(pad "A-41" smd rect
			(at 21.78647 0.12471)
			(size 1.54991 0.24994)
			(layers "F.Cu" "F.Mask" "F.Paste")
		)
		(pad "A-42" smd rect
			(at 25.83624 0.12471)
			(size 1.54991 0.24994)
			(layers "F.Cu" "F.Mask" "F.Paste")
		)
		(pad "A-43" smd rect
			(at 21.78647 0.62484)
			(size 1.54991 0.24994)
			(layers "F.Cu" "F.Mask" "F.Paste")
		)
		(pad "A-44" smd rect
			(at 25.83624 0.62484)
			(size 1.54991 0.24994)
			(layers "F.Cu" "F.Mask" "F.Paste")
			(net "EXT_EEPROM_WP")
		)
		(pad "A-45" smd rect
			(at 21.78647 1.12471)
			(size 1.54991 0.24994)
			(layers "F.Cu" "F.Mask" "F.Paste")
		)
		(pad "A-46" smd rect
			(at 25.83624 1.12471)
			(size 1.54991 0.24994)
			(layers "F.Cu" "F.Mask" "F.Paste")
		)
		(pad "A-47" smd rect
			(at 21.78647 1.62484)
			(size 1.54991 0.24994)
			(layers "F.Cu" "F.Mask" "F.Paste")
		)
		(pad "A-48" smd rect
			(at 25.83624 1.62484)
			(size 1.54991 0.24994)
			(layers "F.Cu" "F.Mask" "F.Paste")
		)
		(pad "A-49" smd rect
			(at 21.78647 2.12471)
			(size 1.54991 0.24994)
			(layers "F.Cu" "F.Mask" "F.Paste")
			(net "GND")
		)
		(pad "A-50" smd rect
			(at 25.83624 2.12471)
			(size 1.54991 0.24994)
			(layers "F.Cu" "F.Mask" "F.Paste")
			(net "GND")
		)
		(pad "A-51" smd rect
			(at 21.78647 2.62484)
			(size 1.54991 0.24994)
			(layers "F.Cu" "F.Mask" "F.Paste")
		)
		(pad "A-52" smd rect
			(at 25.83624 2.62484)
			(size 1.54991 0.24994)
			(layers "F.Cu" "F.Mask" "F.Paste")
		)
		(pad "A-53" smd rect
			(at 21.78647 3.12471)
			(size 1.54991 0.24994)
			(layers "F.Cu" "F.Mask" "F.Paste")
		)
		(pad "A-54" smd rect
			(at 25.83624 3.12471)
			(size 1.54991 0.24994)
			(layers "F.Cu" "F.Mask" "F.Paste")
		)
		(pad "A-55" smd rect
			(at 21.78647 3.62483)
			(size 1.54991 0.24994)
			(layers "F.Cu" "F.Mask" "F.Paste")
		)
		(pad "A-56" smd rect
			(at 25.83624 3.62483)
			(size 1.54991 0.24994)
			(layers "F.Cu" "F.Mask" "F.Paste")
		)
		(pad "A-57" smd rect
			(at 21.78647 4.12471)
			(size 1.54991 0.24994)
			(layers "F.Cu" "F.Mask" "F.Paste")
		)
		(pad "A-58" smd rect
			(at 25.83624 4.12471)
			(size 1.54991 0.24994)
			(layers "F.Cu" "F.Mask" "F.Paste")
		)
		(pad "A-59" smd rect
			(at 21.78647 4.62483)
			(size 1.54991 0.24994)
			(layers "F.Cu" "F.Mask" "F.Paste")
			(net "GND")
		)
		(pad "A-60" smd rect
			(at 25.83624 4.62483)
			(size 1.54991 0.24994)
			(layers "F.Cu" "F.Mask" "F.Paste")
			(net "GND")
		)
		(pad "A-61" smd rect
			(at 21.78647 5.1247)
			(size 1.54991 0.24994)
			(layers "F.Cu" "F.Mask" "F.Paste")
		)
		(pad "A-62" smd rect
			(at 25.83624 5.1247)
			(size 1.54991 0.24994)
			(layers "F.Cu" "F.Mask" "F.Paste")
		)
		(pad "A-63" smd rect
			(at 21.78647 5.62483)
			(size 1.54991 0.24994)
			(layers "F.Cu" "F.Mask" "F.Paste")
		)
		(pad "A-64" smd rect
			(at 25.83624 5.62483)
			(size 1.54991 0.24994)
			(layers "F.Cu" "F.Mask" "F.Paste")
		)
		(pad "A-65" smd rect
			(at 21.78647 6.1247)
			(size 1.54991 0.24994)
			(layers "F.Cu" "F.Mask" "F.Paste")
		)
		(pad "A-66" smd rect
			(at 25.83624 6.1247)
			(size 1.54991 0.24994)
			(layers "F.Cu" "F.Mask" "F.Paste")
		)
		(pad "A-67" smd rect
			(at 21.78647 6.62483)
			(size 1.54991 0.24994)
			(layers "F.Cu" "F.Mask" "F.Paste")
			(net "KEY2")
		)
		(pad "A-68" smd rect
			(at 25.83624 6.62483)
			(size 1.54991 0.24994)
			(layers "F.Cu" "F.Mask" "F.Paste")
		)
		(pad "A-69" smd rect
			(at 21.78647 7.1247)
			(size 1.54991 0.24994)
			(layers "F.Cu" "F.Mask" "F.Paste")
			(net "GND")
		)
		(pad "A-70" smd rect
			(at 25.83624 7.1247)
			(size 1.54991 0.24994)
			(layers "F.Cu" "F.Mask" "F.Paste")
			(net "GND")
		)
		(pad "A-71" smd rect
			(at 21.78647 7.62483)
			(size 1.54991 0.24994)
			(layers "F.Cu" "F.Mask" "F.Paste")
			(net "LED4")
		)
		(pad "A-72" smd rect
			(at 25.83624 7.62483)
			(size 1.54991 0.24994)
			(layers "F.Cu" "F.Mask" "F.Paste")
		)
		(pad "A-73" smd rect
			(at 21.78647 8.1247)
			(size 1.54991 0.24994)
			(layers "F.Cu" "F.Mask" "F.Paste")
			(net "LED3")
		)
		(pad "A-74" smd rect
			(at 25.83624 8.1247)
			(size 1.54991 0.24994)
			(layers "F.Cu" "F.Mask" "F.Paste")
		)
		(pad "A-75" smd rect
			(at 21.78647 8.62482)
			(size 1.54991 0.24994)
			(layers "F.Cu" "F.Mask" "F.Paste")
			(net "LED2")
		)
		(pad "A-76" smd rect
			(at 25.83624 8.62482)
			(size 1.54991 0.24994)
			(layers "F.Cu" "F.Mask" "F.Paste")
		)
		(pad "A-77" smd rect
			(at 21.78647 9.1247)
			(size 1.54991 0.24994)
			(layers "F.Cu" "F.Mask" "F.Paste")
			(net "LED1")
		)
		(pad "A-78" smd rect
			(at 25.83624 9.1247)
			(size 1.54991 0.24994)
			(layers "F.Cu" "F.Mask" "F.Paste")
		)
		(pad "A-79" smd rect
			(at 21.78647 9.62482)
			(size 1.54991 0.24994)
			(layers "F.Cu" "F.Mask" "F.Paste")
		)
		(pad "A-80" smd rect
			(at 25.83624 9.62482)
			(size 1.54991 0.24994)
			(layers "F.Cu" "F.Mask" "F.Paste")
		)
		(pad "A-81" smd rect
			(at 23.8 -11.3)
			(size 1.70002 1.35001)
			(layers "F.Cu" "F.Mask" "F.Paste")
		)
		(pad "A-82" thru_hole circle
			(at 23.81136 -10.1252)
			(size 0.55016 0.55016)
			(drill 0.55016)
			(layers "*.Cu" "*.Mask")
			(remove_unused_layers no)
			(thermal_bridge_angle 90)
		)
		(pad "A-83" thru_hole circle
			(at 23.81136 9.87476)
			(size 0.55016 0.55016)
			(drill 0.55016)
			(layers "*.Cu" "*.Mask")
			(remove_unused_layers no)
			(thermal_bridge_angle 90)
		)
		(pad "A-84" smd rect
			(at 23.8 11.05)
			(size 1.70002 1.35001)
			(layers "F.Cu" "F.Mask" "F.Paste")
		)
		(pad "B-1" smd rect
			(at -10.7014 -16.77035)
			(size 0.24994 1.54991)
			(layers "F.Cu" "F.Mask" "F.Paste")
		)
		(pad "B-2" smd rect
			(at -10.7014 -20.82013)
			(size 0.24994 1.54991)
			(layers "F.Cu" "F.Mask" "F.Paste")
		)
		(pad "B-3" smd rect
			(at -10.20128 -16.77035)
			(size 0.24994 1.54991)
			(layers "F.Cu" "F.Mask" "F.Paste")
		)
		(pad "B-4" smd rect
			(at -10.20128 -20.82013)
			(size 0.24994 1.54991)
			(layers "F.Cu" "F.Mask" "F.Paste")
		)
		(pad "B-5" smd rect
			(at -9.7014 -16.77035)
			(size 0.24994 1.54991)
			(layers "F.Cu" "F.Mask" "F.Paste")
		)
		(pad "B-6" smd rect
			(at -9.7014 -20.82013)
			(size 0.24994 1.54991)
			(layers "F.Cu" "F.Mask" "F.Paste")
		)
		(pad "B-7" smd rect
			(at -9.20128 -16.77035)
			(size 0.24994 1.54991)
			(layers "F.Cu" "F.Mask" "F.Paste")
		)
		(pad "B-8" smd rect
			(at -9.20128 -20.82013)
			(size 0.24994 1.54991)
			(layers "F.Cu" "F.Mask" "F.Paste")
			(net "MAC_USB_PWR")
		)
		(pad "B-9" smd rect
			(at -8.70141 -16.77035)
			(size 0.24994 1.54991)
			(layers "F.Cu" "F.Mask" "F.Paste")
			(net "GND")
		)
		(pad "B-10" smd rect
			(at -8.70141 -20.82013)
			(size 0.24994 1.54991)
			(layers "F.Cu" "F.Mask" "F.Paste")
			(net "GND")
		)
		(pad "B-11" smd rect
			(at -8.20128 -16.77035)
			(size 0.24994 1.54991)
			(layers "F.Cu" "F.Mask" "F.Paste")
			(net "MAC_RF_OUT")
		)
		(pad "B-12" smd rect
			(at -8.20128 -20.82013)
			(size 0.24994 1.54991)
			(layers "F.Cu" "F.Mask" "F.Paste")
		)
		(pad "B-13" smd rect
			(at -7.70141 -16.77035)
			(size 0.24994 1.54991)
			(layers "F.Cu" "F.Mask" "F.Paste")
			(net "MAC_RF_OUT")
		)
		(pad "B-14" smd rect
			(at -7.70141 -20.82013)
			(size 0.24994 1.54991)
			(layers "F.Cu" "F.Mask" "F.Paste")
		)
		(pad "B-15" smd rect
			(at -7.20128 -16.77035)
			(size 0.24994 1.54991)
			(layers "F.Cu" "F.Mask" "F.Paste")
		)
		(pad "B-16" smd rect
			(at -7.20128 -20.82013)
			(size 0.24994 1.54991)
			(layers "F.Cu" "F.Mask" "F.Paste")
		)
		(pad "B-17" smd rect
			(at -6.70141 -16.77035)
			(size 0.24994 1.54991)
			(layers "F.Cu" "F.Mask" "F.Paste")
		)
		(pad "B-18" smd rect
			(at -6.70141 -20.82013)
			(size 0.24994 1.54991)
			(layers "F.Cu" "F.Mask" "F.Paste")
		)
		(pad "B-19" smd rect
			(at -6.20128 -16.77035)
			(size 0.24994 1.54991)
			(layers "F.Cu" "F.Mask" "F.Paste")
			(net "GND")
		)
		(pad "B-20" smd rect
			(at -6.20128 -20.82013)
			(size 0.24994 1.54991)
			(layers "F.Cu" "F.Mask" "F.Paste")
			(net "GND")
		)
		(pad "B-21" smd rect
			(at -5.70141 -16.77035)
			(size 0.24994 1.54991)
			(layers "F.Cu" "F.Mask" "F.Paste")
			(net "ANT1")
		)
		(pad "B-22" smd rect
			(at -5.70141 -20.82013)
			(size 0.24994 1.54991)
			(layers "F.Cu" "F.Mask" "F.Paste")
		)
		(pad "B-23" smd rect
			(at -5.20129 -16.77035)
			(size 0.24994 1.54991)
			(layers "F.Cu" "F.Mask" "F.Paste")
			(net "ANT2")
		)
		(pad "B-24" smd rect
			(at -5.20129 -20.82013)
			(size 0.24994 1.54991)
			(layers "F.Cu" "F.Mask" "F.Paste")
		)
		(pad "B-25" smd rect
			(at -4.70141 -16.77035)
			(size 0.24994 1.54991)
			(layers "F.Cu" "F.Mask" "F.Paste")
			(net "ANT3")
		)
		(pad "B-26" smd rect
			(at -4.70141 -20.82013)
			(size 0.24994 1.54991)
			(layers "F.Cu" "F.Mask" "F.Paste")
			(net "MAC_TX")
		)
		(pad "B-27" smd rect
			(at -4.20129 -16.77035)
			(size 0.24994 1.54991)
			(layers "F.Cu" "F.Mask" "F.Paste")
			(net "ANT4")
		)
		(pad "B-28" smd rect
			(at -4.20129 -20.82013)
			(size 0.24994 1.54991)
			(layers "F.Cu" "F.Mask" "F.Paste")
			(net "MAC_RX")
		)
		(pad "B-29" smd rect
			(at -3.70142 -16.77035)
			(size 0.24994 1.54991)
			(layers "F.Cu" "F.Mask" "F.Paste")
			(net "GND")
		)
		(pad "B-30" smd rect
			(at -3.70142 -20.82013)
			(size 0.24994 1.54991)
			(layers "F.Cu" "F.Mask" "F.Paste")
			(net "GND")
		)
		(pad "B-31" smd rect
			(at -3.20129 -16.77035)
			(size 0.24994 1.54991)
			(layers "F.Cu" "F.Mask" "F.Paste")
		)
		(pad "B-32" smd rect
			(at -3.20129 -20.82013)
			(size 0.24994 1.54991)
			(layers "F.Cu" "F.Mask" "F.Paste")
		)
		(pad "B-33" smd rect
			(at -2.70142 -16.77035)
			(size 0.24994 1.54991)
			(layers "F.Cu" "F.Mask" "F.Paste")
			(net "MAC_FREQ_CTRL")
		)
		(pad "B-34" smd rect
			(at -2.70142 -20.82013)
			(size 0.24994 1.54991)
			(layers "F.Cu" "F.Mask" "F.Paste")
		)
		(pad "B-35" smd rect
			(at -2.20129 -16.77035)
			(size 0.24994 1.54991)
			(layers "F.Cu" "F.Mask" "F.Paste")
			(net "MAC_ALARM")
		)
		(pad "B-36" smd rect
			(at -2.20129 -20.82013)
			(size 0.24994 1.54991)
			(layers "F.Cu" "F.Mask" "F.Paste")
		)
		(pad "B-37" smd rect
			(at -1.70142 -16.77035)
			(size 0.24994 1.54991)
			(layers "F.Cu" "F.Mask" "F.Paste")
			(net "MAC_BITE")
		)
		(pad "B-38" smd rect
			(at -1.70142 -20.82013)
			(size 0.24994 1.54991)
			(layers "F.Cu" "F.Mask" "F.Paste")
		)
		(pad "B-39" smd rect
			(at -1.20129 -16.77035)
			(size 0.24994 1.54991)
			(layers "F.Cu" "F.Mask" "F.Paste")
			(net "GND")
		)
		(pad "B-40" smd rect
			(at -1.20129 -20.82013)
			(size 0.24994 1.54991)
			(layers "F.Cu" "F.Mask" "F.Paste")
			(net "GND")
		)
		(pad "B-41" smd rect
			(at -0.70142 -16.77035)
			(size 0.24994 1.54991)
			(layers "F.Cu" "F.Mask" "F.Paste")
		)
		(pad "B-42" smd rect
			(at -0.70142 -20.82013)
			(size 0.24994 1.54991)
			(layers "F.Cu" "F.Mask" "F.Paste")
		)
		(pad "B-43" smd rect
			(at -0.2013 -16.77035)
			(size 0.24994 1.54991)
			(layers "F.Cu" "F.Mask" "F.Paste")
			(net "FPGA_MAC_PPS_OUT-")
		)
		(pad "B-44" smd rect
			(at -0.2013 -20.82013)
			(size 0.24994 1.54991)
			(layers "F.Cu" "F.Mask" "F.Paste")
		)
		(pad "B-45" smd rect
			(at 0.29858 -16.77035)
			(size 0.24994 1.54991)
			(layers "F.Cu" "F.Mask" "F.Paste")
		)
		(pad "B-46" smd rect
			(at 0.29858 -20.82013)
			(size 0.24994 1.54991)
			(layers "F.Cu" "F.Mask" "F.Paste")
		)
		(pad "B-47" smd rect
			(at 0.7987 -16.77035)
			(size 0.24994 1.54991)
			(layers "F.Cu" "F.Mask" "F.Paste")
			(net "FPGA_MAC_PPS_IN0-")
		)
		(pad "B-48" smd rect
			(at 0.7987 -20.82013)
			(size 0.24994 1.54991)
			(layers "F.Cu" "F.Mask" "F.Paste")
		)
		(pad "B-49" smd rect
			(at 1.29857 -16.77035)
			(size 0.24994 1.54991)
			(layers "F.Cu" "F.Mask" "F.Paste")
			(net "GND")
		)
	)
)
